(kicad_pcb
	(version 20241229)
	(generator "pcbnew")
	(generator_version "9.0")
	(general
		(thickness 1.294)
		(legacy_teardrops no)
	)
	(paper "A3")
	(title_block
		(title "Kintex 410T devboard")
		(date "2024-04-03")
		(rev "1.1.2")
		(comment 9 "footprints 904-909 of 975")
	)
	(layers
		(0 "F.Cu" mixed)
		(4 "In1.Cu" power)
		(6 "In2.Cu" power)
		(8 "In3.Cu" mixed)
		(10 "In4.Cu" power)
		(12 "In5.Cu" mixed)
		(14 "In6.Cu" power)
		(16 "In7.Cu" mixed)
		(18 "In8.Cu" power)
		(2 "B.Cu" mixed)
		(9 "F.Adhes" user "F.Adhesive")
		(11 "B.Adhes" user "B.Adhesive")
		(13 "F.Paste" user)
		(15 "B.Paste" user)
		(5 "F.SilkS" user "F.Silkscreen")
		(7 "B.SilkS" user "B.Silkscreen")
		(1 "F.Mask" user)
		(3 "B.Mask" user)
		(17 "Dwgs.User" user "User.Drawings")
		(19 "Cmts.User" user "User.Comments")
		(21 "Eco1.User" user "User.Eco1")
		(23 "Eco2.User" user "User.Eco2")
		(25 "Edge.Cuts" user)
		(27 "Margin" user)
		(31 "F.CrtYd" user "F.Courtyard")
		(29 "B.CrtYd" user "B.Courtyard")
		(35 "F.Fab" user)
		(33 "B.Fab" user)
	)
	(footprint "antmicro-footprints:R_0402_1005Metric"
		(layer "B.Cu")
		(at 195.691252 96.85 180)
		(descr "Resistor SMD 0402")
		(tags "resistor SMD 0402")
		(property "Reference" "R203"
			(at 0.716252 -0.425 0)
			(layer "B.SilkS")
			(effects
				(font
					(size 0.7 0.7)
					(thickness 0.15)
				)
				(justify left bottom mirror)
			)
		)
		(property "Value" "R_10k_0402"
			(at 0 -1.4 0)
			(layer "B.Fab")
			(effects
				(font
					(size 0.7 0.7)
					(thickness 0.15)
				)
				(justify left bottom mirror)
			)
		)
		(property "Description" "SMD Chip Resistor, 10 kohm, ± 1%, 62.5 mW, 0402 [1005 Metric], Thick Film, General Purpose"
			(at 0 0 180)
			(layer "F.Fab")
			(hide yes)
			(effects
				(font
					(size 1.27 1.27)
					(thickness 0.15)
				)
			)
		)
		(property "Author" "Antmicro"
			(at 391.382504 193.7 0)
			(layer "B.Fab")
			(hide yes)
			(effects
				(font
					(size 1 1)
					(thickness 0.15)
				)
				(justify mirror)
			)
		)
		(property "DNP" "DNP"
			(at 391.382504 193.7 0)
			(layer "B.Fab")
			(hide yes)
			(effects
				(font
					(size 1 1)
					(thickness 0.15)
				)
				(justify mirror)
			)
		)
		(property "License" "Apache-2.0"
			(at 391.382504 193.7 0)
			(layer "B.Fab")
			(hide yes)
			(effects
				(font
					(size 1 1)
					(thickness 0.15)
				)
				(justify mirror)
			)
		)
		(property "MPN" "CR0402-FX-1002GLF"
			(at 391.382504 193.7 0)
			(layer "B.Fab")
			(hide yes)
			(effects
				(font
					(size 1 1)
					(thickness 0.15)
				)
				(justify mirror)
			)
		)
		(property "Manufacturer" "Bourns"
			(at 391.382504 193.7 0)
			(layer "B.Fab")
			(hide yes)
			(effects
				(font
					(size 1 1)
					(thickness 0.15)
				)
				(justify mirror)
			)
		)
		(property "Tolerance" "1%"
			(at 391.382504 193.7 0)
			(layer "B.Fab")
			(hide yes)
			(effects
				(font
					(size 1 1)
					(thickness 0.15)
				)
				(justify mirror)
			)
		)
		(property "Val" "10k"
			(at 391.382504 193.7 0)
			(layer "B.Fab")
			(hide yes)
			(effects
				(font
					(size 1 1)
					(thickness 0.15)
				)
				(justify mirror)
			)
		)
		(property "dnp" ""
			(at 391.382504 193.7 0)
			(layer "B.Fab")
			(hide yes)
			(effects
				(font
					(size 1 1)
					(thickness 0.15)
				)
				(justify mirror)
			)
		)
		(property "exclude_from_bom" ""
			(at 391.382504 193.7 0)
			(layer "B.Fab")
			(hide yes)
			(effects
				(font
					(size 1 1)
					(thickness 0.15)
				)
				(justify mirror)
			)
		)
		(sheetname "HDMI + Ethernet")
		(sheetfile "hdmi-ethernet.kicad_sch")
		(attr smd exclude_from_bom)
		(fp_rect
			(start -0.925 0.47)
			(end 0.925 -0.47)
			(stroke
				(width 0.05)
				(type default)
			)
			(fill no)
			(layer "B.CrtYd")
		)
		(fp_rect
			(start -0.5 0.25)
			(end 0.5 -0.25)
			(stroke
				(width 0.15)
				(type solid)
			)
			(fill no)
			(layer "B.Fab")
		)
		(pad "1" smd roundrect
			(at -0.48 0 180)
			(size 0.59 0.64)
			(layers "B.Cu" "B.Mask" "B.Paste")
			(roundrect_rratio 0.25)
			(net 507 "/FPGA Bank 16 & 17/GBE_RGMII.GTR_CLK")
			(pintype "passive")
		)
		(pad "2" smd roundrect
			(at 0.48 0 180)
			(size 0.59 0.64)
			(layers "B.Cu" "B.Mask" "B.Paste")
			(roundrect_rratio 0.25)
			(net 24 "+3V3")
			(pintype "passive")
		)
	)
	(footprint "antmicro-footprints:C_0201"
		(layer "B.Cu")
		(at 201.5 128.85 180)
		(descr "Capacitor SMD 0201")
		(tags "capacitor SMD 0201")
		(property "Reference" "C60"
			(at -26.9 29.025 0)
			(layer "B.SilkS")
			(effects
				(font
					(size 0.7 0.7)
					(thickness 0.15)
				)
				(justify left bottom mirror)
			)
		)
		(property "Value" "C_100n_0201"
			(at 0 -1.4 0)
			(layer "B.Fab")
			(effects
				(font
					(size 0.7 0.7)
					(thickness 0.15)
				)
				(justify left bottom mirror)
			)
		)
		(property "Description" "SMD Multilayer Ceramic Capacitor, 0.1 µF, 6.3 V, 0201 [0603 Metric], ± 10%, X6S, CC Series"
			(at 0 0 180)
			(layer "F.Fab")
			(hide yes)
			(effects
				(font
					(size 1.27 1.27)
					(thickness 0.15)
				)
			)
		)
		(property "Author" "Antmicro"
			(at 403 257.7 0)
			(layer "B.Fab")
			(hide yes)
			(effects
				(font
					(size 1 1)
					(thickness 0.15)
				)
				(justify mirror)
			)
		)
		(property "Dielectric" ""
			(at 403 257.7 0)
			(layer "B.Fab")
			(hide yes)
			(effects
				(font
					(size 1 1)
					(thickness 0.15)
				)
				(justify mirror)
			)
		)
		(property "License" "Apache-2.0"
			(at 403 257.7 0)
			(layer "B.Fab")
			(hide yes)
			(effects
				(font
					(size 1 1)
					(thickness 0.15)
				)
				(justify mirror)
			)
		)
		(property "MPN" "CC0201KRX6S5BB104"
			(at 403 257.7 0)
			(layer "B.Fab")
			(hide yes)
			(effects
				(font
					(size 1 1)
					(thickness 0.15)
				)
				(justify mirror)
			)
		)
		(property "Manufacturer" "YAGEO"
			(at 403 257.7 0)
			(layer "B.Fab")
			(hide yes)
			(effects
				(font
					(size 1 1)
					(thickness 0.15)
				)
				(justify mirror)
			)
		)
		(property "Val" "100n"
			(at 403 257.7 0)
			(layer "B.Fab")
			(hide yes)
			(effects
				(font
					(size 1 1)
					(thickness 0.15)
				)
				(justify mirror)
			)
		)
		(property "Voltage" ""
			(at 403 257.7 0)
			(layer "B.Fab")
			(hide yes)
			(effects
				(font
					(size 1 1)
					(thickness 0.15)
				)
				(justify mirror)
			)
		)
		(sheetname "FPGA supply")
		(sheetfile "fpga-supply.kicad_sch")
		(attr smd)
		(fp_rect
			(start -0.7 0.35)
			(end 0.7 -0.35)
			(stroke
				(width 0.05)
				(type default)
			)
			(fill no)
			(layer "B.CrtYd")
		)
		(fp_rect
			(start 0.3 -0.15)
			(end -0.301 0.149)
			(stroke
				(width 0.15)
				(type solid)
			)
			(fill no)
			(layer "B.Fab")
		)
		(pad "" smd roundrect
			(at -0.349 0.002 180)
			(size 0.318 0.36)
			(layers "B.Paste")
			(roundrect_rratio 0.25)
		)
		(pad "" smd roundrect
			(at 0.341 0.002 180)
			(size 0.318 0.36)
			(layers "B.Paste")
			(roundrect_rratio 0.25)
		)
		(pad "1" smd roundrect
			(at -0.321 0.002 180)
			(size 0.46 0.4)
			(layers "B.Cu" "B.Mask")
			(roundrect_rratio 0.25)
			(net 1 "GND")
			(pintype "passive")
		)
		(pad "2" smd roundrect
			(at 0.32 0.002 180)
			(size 0.46 0.4)
			(layers "B.Cu" "B.Mask")
			(roundrect_rratio 0.25)
			(net 650 "+1V0")
			(pintype "passive")
		)
	)
	(footprint "antmicro-footprints:C_0402_1005Metric"
		(layer "B.Cu")
		(at 194.475 134.175 180)
		(descr "Capacitor SMD 0402")
		(tags "capacitor SMD 0402")
		(property "Reference" "C64"
			(at -24.125 28.025 0)
			(layer "B.SilkS")
			(effects
				(font
					(size 0.7 0.7)
					(thickness 0.15)
				)
				(justify left bottom mirror)
			)
		)
		(property "Value" "C_100n_0402"
			(at 0 -1.169 0)
			(layer "B.Fab")
			(effects
				(font
					(size 0.7 0.7)
					(thickness 0.15)
				)
				(justify left bottom mirror)
			)
		)
		(property "Description" "SMD Multilayer Ceramic Capacitor, 0.1 µF, 50 V, 0402 [1005 Metric], ± 10%, X5R, GRM Series"
			(at 0 0 180)
			(layer "F.Fab")
			(hide yes)
			(effects
				(font
					(size 1.27 1.27)
					(thickness 0.15)
				)
			)
		)
		(property "Author" "Antmicro"
			(at 388.95 268.35 0)
			(layer "B.Fab")
			(hide yes)
			(effects
				(font
					(size 1 1)
					(thickness 0.15)
				)
				(justify mirror)
			)
		)
		(property "Dielectric" "X5R"
			(at 388.95 268.35 0)
			(layer "B.Fab")
			(hide yes)
			(effects
				(font
					(size 1 1)
					(thickness 0.15)
				)
				(justify mirror)
			)
		)
		(property "License" "Apache-2.0"
			(at 388.95 268.35 0)
			(layer "B.Fab")
			(hide yes)
			(effects
				(font
					(size 1 1)
					(thickness 0.15)
				)
				(justify mirror)
			)
		)
		(property "MPN" "GRM155R61H104KE14D"
			(at 388.95 268.35 0)
			(layer "B.Fab")
			(hide yes)
			(effects
				(font
					(size 1 1)
					(thickness 0.15)
				)
				(justify mirror)
			)
		)
		(property "Manufacturer" "Murata"
			(at 388.95 268.35 0)
			(layer "B.Fab")
			(hide yes)
			(effects
				(font
					(size 1 1)
					(thickness 0.15)
				)
				(justify mirror)
			)
		)
		(property "Val" "100n"
			(at 388.95 268.35 0)
			(layer "B.Fab")
			(hide yes)
			(effects
				(font
					(size 1 1)
					(thickness 0.15)
				)
				(justify mirror)
			)
		)
		(property "Voltage" "50V"
			(at 388.95 268.35 0)
			(layer "B.Fab")
			(hide yes)
			(effects
				(font
					(size 1 1)
					(thickness 0.15)
				)
				(justify mirror)
			)
		)
		(sheetname "FPGA supply")
		(sheetfile "fpga-supply.kicad_sch")
		(attr smd)
		(fp_rect
			(start -0.925 0.47)
			(end 0.925 -0.47)
			(stroke
				(width 0.05)
				(type default)
			)
			(fill no)
			(layer "B.CrtYd")
		)
		(fp_line
			(start 0.504 0.25)
			(end 0.504 -0.248)
			(stroke
				(width 0.15)
				(type solid)
			)
			(layer "B.Fab")
		)
		(fp_line
			(start 0.504 -0.248)
			(end -0.494 -0.248)
			(stroke
				(width 0.15)
				(type solid)
			)
			(layer "B.Fab")
		)
		(fp_line
			(start -0.494 0.25)
			(end 0.504 0.25)
			(stroke
				(width 0.15)
				(type solid)
			)
			(layer "B.Fab")
		)
		(fp_line
			(start -0.494 -0.248)
			(end -0.494 0.25)
			(stroke
				(width 0.15)
				(type solid)
			)
			(layer "B.Fab")
		)
		(pad "1" smd roundrect
			(at -0.48 0 180)
			(size 0.59 0.64)
			(layers "B.Cu" "B.Mask" "B.Paste")
			(roundrect_rratio 0.25)
			(net 1 "GND")
			(pintype "passive")
		)
		(pad "2" smd roundrect
			(at 0.48 0 180)
			(size 0.59 0.64)
			(layers "B.Cu" "B.Mask" "B.Paste")
			(roundrect_rratio 0.25)
			(net 26 "+1V8")
			(pintype "passive")
		)
	)
	(footprint "antmicro-footprints:R_0402_1005Metric"
		(layer "B.Cu")
		(at 220.6 123.8 180)
		(descr "Resistor SMD 0402")
		(tags "resistor SMD 0402")
		(property "Reference" "R106"
			(at -1.325 2.5 0)
			(layer "B.SilkS")
			(effects
				(font
					(size 0.7 0.7)
					(thickness 0.15)
				)
				(justify left bottom mirror)
			)
		)
		(property "Value" "R_1k_0402"
			(at 0 -1.4 0)
			(layer "B.Fab")
			(effects
				(font
					(size 0.7 0.7)
					(thickness 0.15)
				)
				(justify left bottom mirror)
			)
		)
		(property "Description" "SMD Chip Resistor, 1 kohm, ± 1%, 63 mW, 0402 [1005 Metric], Thick Film, General Purpose"
			(at 0 0 180)
			(layer "F.Fab")
			(hide yes)
			(effects
				(font
					(size 1.27 1.27)
					(thickness 0.15)
				)
			)
		)
		(property "Author" "Antmicro"
			(at 441.2 247.6 0)
			(layer "B.Fab")
			(hide yes)
			(effects
				(font
					(size 1 1)
					(thickness 0.15)
				)
				(justify mirror)
			)
		)
		(property "License" "Apache-2.0"
			(at 441.2 247.6 0)
			(layer "B.Fab")
			(hide yes)
			(effects
				(font
					(size 1 1)
					(thickness 0.15)
				)
				(justify mirror)
			)
		)
		(property "MPN" "CR0402-FX-1001GLF"
			(at 441.2 247.6 0)
			(layer "B.Fab")
			(hide yes)
			(effects
				(font
					(size 1 1)
					(thickness 0.15)
				)
				(justify mirror)
			)
		)
		(property "Manufacturer" "Bourns"
			(at 441.2 247.6 0)
			(layer "B.Fab")
			(hide yes)
			(effects
				(font
					(size 1 1)
					(thickness 0.15)
				)
				(justify mirror)
			)
		)
		(property "Tolerance" "1%"
			(at 441.2 247.6 0)
			(layer "B.Fab")
			(hide yes)
			(effects
				(font
					(size 1 1)
					(thickness 0.15)
				)
				(justify mirror)
			)
		)
		(property "Val" "1k"
			(at 441.2 247.6 0)
			(layer "B.Fab")
			(hide yes)
			(effects
				(font
					(size 1 1)
					(thickness 0.15)
				)
				(justify mirror)
			)
		)
		(sheetname "User GPIO + LED + button + DIP switch")
		(sheetfile "user-gpio.kicad_sch")
		(attr smd)
		(fp_rect
			(start -0.925 0.47)
			(end 0.925 -0.47)
			(stroke
				(width 0.05)
				(type default)
			)
			(fill no)
			(layer "B.CrtYd")
		)
		(fp_rect
			(start -0.5 0.25)
			(end 0.5 -0.25)
			(stroke
				(width 0.15)
				(type solid)
			)
			(fill no)
			(layer "B.Fab")
		)
		(pad "1" smd roundrect
			(at -0.48 0 180)
			(size 0.59 0.64)
			(layers "B.Cu" "B.Mask" "B.Paste")
			(roundrect_rratio 0.25)
			(net 876 "/User GPIO + LED + button + DIP switch/FAN_PWM_CTRL_AON")
			(pintype "passive")
		)
		(pad "2" smd roundrect
			(at 0.48 0 180)
			(size 0.59 0.64)
			(layers "B.Cu" "B.Mask" "B.Paste")
			(roundrect_rratio 0.25)
			(net 24 "+3V3")
			(pintype "passive")
		)
	)
	(footprint "antmicro-footprints:C_0603_1608Metric"
		(layer "B.Cu")
		(at 195.125 147.25)
		(descr "Capacitor SMD 0603")
		(tags "capacitor 0603")
		(property "Reference" "C54"
			(at -1.045 1.47 0)
			(layer "B.SilkS")
			(effects
				(font
					(size 0.7 0.7)
					(thickness 0.15)
				)
				(justify right bottom mirror)
			)
		)
		(property "Value" "C_47u_0603"
			(at 0 -1.6 0)
			(layer "B.Fab")
			(effects
				(font
					(size 0.7 0.7)
					(thickness 0.15)
				)
				(justify right bottom mirror)
			)
		)
		(property "Description" "SMD Multilayer Ceramic Capacitor, 47 µF, 6.3 V, 0603 [1608 Metric], ± 20%, X5R, GRM Series"
			(at 0 0 0)
			(layer "F.Fab")
			(hide yes)
			(effects
				(font
					(size 1.27 1.27)
					(thickness 0.15)
				)
			)
		)
		(property "Author" "Antmicro"
			(at 0 0 0)
			(layer "B.Fab")
			(hide yes)
			(effects
				(font
					(size 1 1)
					(thickness 0.15)
				)
				(justify mirror)
			)
		)
		(property "Dielectric" ""
			(at 0 0 0)
			(layer "B.Fab")
			(hide yes)
			(effects
				(font
					(size 1 1)
					(thickness 0.15)
				)
				(justify mirror)
			)
		)
		(property "License" "Apache-2.0"
			(at 0 0 0)
			(layer "B.Fab")
			(hide yes)
			(effects
				(font
					(size 1 1)
					(thickness 0.15)
				)
				(justify mirror)
			)
		)
		(property "MPN" "GRM188R60J476ME15D"
			(at 0 0 0)
			(layer "B.Fab")
			(hide yes)
			(effects
				(font
					(size 1 1)
					(thickness 0.15)
				)
				(justify mirror)
			)
		)
		(property "Manufacturer" "Murata"
			(at 0 0 0)
			(layer "B.Fab")
			(hide yes)
			(effects
				(font
					(size 1 1)
					(thickness 0.15)
				)
				(justify mirror)
			)
		)
		(property "Val" "47u"
			(at 0 0 0)
			(layer "B.Fab")
			(hide yes)
			(effects
				(font
					(size 1 1)
					(thickness 0.15)
				)
				(justify mirror)
			)
		)
		(property "Voltage" ""
			(at 0 0 0)
			(layer "B.Fab")
			(hide yes)
			(effects
				(font
					(size 1 1)
					(thickness 0.15)
				)
				(justify mirror)
			)
		)
		(sheetname "FPGA supply")
		(sheetfile "fpga-supply.kicad_sch")
		(attr smd)
		(fp_line
			(start -0.15 -0.4)
			(end 0.15 -0.4)
			(stroke
				(width 0.15)
				(type solid)
			)
			(layer "B.SilkS")
		)
		(fp_line
			(start -0.15 0.4)
			(end 0.15 0.4)
			(stroke
				(width 0.15)
				(type solid)
			)
			(layer "B.SilkS")
		)
		(fp_rect
			(start -1.25 0.65)
			(end 1.25 -0.65)
			(stroke
				(width 0.05)
				(type solid)
			)
			(fill no)
			(layer "B.CrtYd")
		)
		(fp_rect
			(start -0.8 0.4)
			(end 0.8 -0.4)
			(stroke
				(width 0.15)
				(type solid)
			)
			(fill no)
			(layer "B.Fab")
		)
		(pad "1" smd roundrect
			(at -0.7 0)
			(size 0.8 1)
			(layers "B.Cu" "B.Mask" "B.Paste")
			(roundrect_rratio 0.2)
			(net 1 "GND")
			(pintype "passive")
		)
		(pad "2" smd roundrect
			(at 0.7 0)
			(size 0.8 1)
			(layers "B.Cu" "B.Mask" "B.Paste")
			(roundrect_rratio 0.2)
			(net 26 "+1V8")
			(pintype "passive")
		)
	)
	(footprint "antmicro-footprints:C_0402_1005Metric"
		(layer "B.Cu")
		(at 168.6 188.2 -90)
		(descr "Capacitor SMD 0402")
		(tags "capacitor SMD 0402")
		(property "Reference" "C339"
			(at -1.8 -1.275 90)
			(layer "B.SilkS")
			(effects
				(font
					(size 0.7 0.7)
					(thickness 0.15)
				)
				(justify left bottom mirror)
			)
		)
		(property "Value" "C_100n_0402"
			(at 0 -1.4 90)
			(layer "B.Fab")
			(effects
				(font
					(size 0.7 0.7)
					(thickness 0.15)
				)
				(justify left bottom mirror)
			)
		)
		(property "Description" "SMD Multilayer Ceramic Capacitor, 0.1 µF, 50 V, 0402 [1005 Metric], ± 10%, X5R, GRM Series"
			(at 0 0 270)
			(layer "F.Fab")
			(hide yes)
			(effects
				(font
					(size 1.27 1.27)
					(thickness 0.15)
				)
			)
		)
		(property "Author" "Antmicro"
			(at -19.6 356.8 0)
			(layer "B.Fab")
			(hide yes)
			(effects
				(font
					(size 1 1)
					(thickness 0.15)
				)
				(justify mirror)
			)
		)
		(property "DNP" "DNP"
			(at -19.6 356.8 0)
			(layer "B.Fab")
			(hide yes)
			(effects
				(font
					(size 1 1)
					(thickness 0.15)
				)
				(justify mirror)
			)
		)
		(property "Dielectric" "X5R"
			(at -19.6 356.8 0)
			(layer "B.Fab")
			(hide yes)
			(effects
				(font
					(size 1 1)
					(thickness 0.15)
				)
				(justify mirror)
			)
		)
		(property "License" "Apache-2.0"
			(at -19.6 356.8 0)
			(layer "B.Fab")
			(hide yes)
			(effects
				(font
					(size 1 1)
					(thickness 0.15)
				)
				(justify mirror)
			)
		)
		(property "MPN" "GRM155R61H104KE14D"
			(at -19.6 356.8 0)
			(layer "B.Fab")
			(hide yes)
			(effects
				(font
					(size 1 1)
					(thickness 0.15)
				)
				(justify mirror)
			)
		)
		(property "Manufacturer" "Murata"
			(at -19.6 356.8 0)
			(layer "B.Fab")
			(hide yes)
			(effects
				(font
					(size 1 1)
					(thickness 0.15)
				)
				(justify mirror)
			)
		)
		(property "Val" "100n"
			(at -19.6 356.8 0)
			(layer "B.Fab")
			(hide yes)
			(effects
				(font
					(size 1 1)
					(thickness 0.15)
				)
				(justify mirror)
			)
		)
		(property "Voltage" "50V"
			(at -19.6 356.8 0)
			(layer "B.Fab")
			(hide yes)
			(effects
				(font
					(size 1 1)
					(thickness 0.15)
				)
				(justify mirror)
			)
		)
		(property "dnp" ""
			(at -19.6 356.8 0)
			(layer "B.Fab")
			(hide yes)
			(effects
				(font
					(size 1 1)
					(thickness 0.15)
				)
				(justify mirror)
			)
		)
		(property "exclude_from_bom" ""
			(at -19.6 356.8 0)
			(layer "B.Fab")
			(hide yes)
			(effects
				(font
					(size 1 1)
					(thickness 0.15)
				)
				(justify mirror)
			)
		)
		(sheetname "DC-DC Converters")
		(sheetfile "dc-dc.kicad_sch")
		(attr smd exclude_from_bom)
		(fp_rect
			(start -0.925 0.47)
			(end 0.925 -0.47)
			(stroke
				(width 0.05)
				(type default)
			)
			(fill no)
			(layer "B.CrtYd")
		)
		(fp_line
			(start -0.494 0.25)
			(end 0.504 0.25)
			(stroke
				(width 0.15)
				(type solid)
			)
			(layer "B.Fab")
		)
		(fp_line
			(start 0.504 0.25)
			(end 0.504 -0.248)
			(stroke
				(width 0.15)
				(type solid)
			)
			(layer "B.Fab")
		)
		(fp_line
			(start -0.494 -0.248)
			(end -0.494 0.25)
			(stroke
				(width 0.15)
				(type solid)
			)
			(layer "B.Fab")
		)
		(fp_line
			(start 0.504 -0.248)
			(end -0.494 -0.248)
			(stroke
				(width 0.15)
				(type solid)
			)
			(layer "B.Fab")
		)
		(pad "1" smd roundrect
			(at -0.48 0 270)
			(size 0.59 0.64)
			(layers "B.Cu" "B.Mask" "B.Paste")
			(roundrect_rratio 0.25)
			(net 1 "GND")
			(pintype "passive")
		)
		(pad "2" smd roundrect
			(at 0.48 0 270)
			(size 0.59 0.64)
			(layers "B.Cu" "B.Mask" "B.Paste")
			(roundrect_rratio 0.25)
			(net 14 "/DC-DC Converters/SEQ_EN")
			(pintype "passive")
		)
	)
)
